(kicad_pcb
	(version 20241229)
	(generator "pcbnew")
	(generator_version "9.0")
	(general
		(thickness 1.62)
		(legacy_teardrops no)
	)
	(paper "A3")
	(title_block
		(title "COM Express 7 Baseboard")
		(date "2025-02-04")
		(rev "1.1.2")
		(company "Antmicro Ltd")
		(comment 1 "www.antmicro.com")
		(comment 9 "footprints 751-756 of 802")
	)
	(layers
		(0 "F.Cu" signal)
		(4 "In1.Cu" signal)
		(6 "In2.Cu" signal)
		(8 "In3.Cu" signal)
		(10 "In4.Cu" signal)
		(12 "In5.Cu" signal)
		(14 "In6.Cu" signal)
		(2 "B.Cu" signal)
		(9 "F.Adhes" user "F.Adhesive")
		(11 "B.Adhes" user "B.Adhesive")
		(13 "F.Paste" user)
		(15 "B.Paste" user)
		(5 "F.SilkS" user "F.Silkscreen")
		(7 "B.SilkS" user "B.Silkscreen")
		(1 "F.Mask" user)
		(3 "B.Mask" user)
		(17 "Dwgs.User" user "User.Drawings")
		(19 "Cmts.User" user "User.Comments")
		(21 "Eco1.User" user "User.Eco1")
		(23 "Eco2.User" user "User.Eco2")
		(25 "Edge.Cuts" user)
		(27 "Margin" user)
		(31 "F.CrtYd" user "F.Courtyard")
		(29 "B.CrtYd" user "B.Courtyard")
		(35 "F.Fab" user)
		(33 "B.Fab" user)
	)
	(footprint "antmicro-footprints:C_0402_1005Metric"
		(layer "B.Cu")
		(at 133.29 132.36 -90)
		(descr "Capacitor SMD 0402")
		(tags "capacitor SMD 0402")
		(property "Reference" "C192"
			(at -3.7 -0.41 90)
			(layer "B.SilkS")
			(effects
				(font
					(size 0.7 0.7)
					(thickness 0.15)
				)
				(justify left bottom mirror)
			)
		)
		(property "Value" "C_100n_0402"
			(at -1.022927 -2.155213 90)
			(layer "B.Fab")
			(effects
				(font
					(size 0.7 0.7)
					(thickness 0.15)
				)
				(justify left bottom mirror)
			)
		)
		(property "Datasheet" "https://www.murata.com/products/productdetail?partno=GRM155R61H104KE14%23"
			(at 0 0 270)
			(layer "F.Fab")
			(hide yes)
			(effects
				(font
					(size 1.27 1.27)
					(thickness 0.15)
				)
			)
		)
		(property "Author" "Antmicro"
			(at 0.93 265.65 0)
			(layer "B.Fab")
			(hide yes)
			(effects
				(font
					(size 1 1)
					(thickness 0.15)
				)
				(justify mirror)
			)
		)
		(property "Dielectric" "X5R"
			(at 0.93 265.65 0)
			(layer "B.Fab")
			(hide yes)
			(effects
				(font
					(size 1 1)
					(thickness 0.15)
				)
				(justify mirror)
			)
		)
		(property "License" "Apache-2.0"
			(at 0.93 265.65 0)
			(layer "B.Fab")
			(hide yes)
			(effects
				(font
					(size 1 1)
					(thickness 0.15)
				)
				(justify mirror)
			)
		)
		(property "MPN" "GRM155R61H104KE14D"
			(at 0.93 265.65 0)
			(layer "B.Fab")
			(hide yes)
			(effects
				(font
					(size 1 1)
					(thickness 0.15)
				)
				(justify mirror)
			)
		)
		(property "Manufacturer" "Murata"
			(at 0.93 265.65 0)
			(layer "B.Fab")
			(hide yes)
			(effects
				(font
					(size 1 1)
					(thickness 0.15)
				)
				(justify mirror)
			)
		)
		(property "Public" "False"
			(at 0.93 265.65 0)
			(layer "B.Fab")
			(hide yes)
			(effects
				(font
					(size 1 1)
					(thickness 0.15)
				)
				(justify mirror)
			)
		)
		(property "Val" "100n"
			(at 0.93 265.65 0)
			(layer "B.Fab")
			(hide yes)
			(effects
				(font
					(size 1 1)
					(thickness 0.15)
				)
				(justify mirror)
			)
		)
		(property "Voltage" "50V"
			(at 0.93 265.65 0)
			(layer "B.Fab")
			(hide yes)
			(effects
				(font
					(size 1 1)
					(thickness 0.15)
				)
				(justify mirror)
			)
		)
		(sheetname "KR to SFI #2")
		(sheetfile "kr_sfi.kicad_sch")
		(attr smd)
		(fp_rect
			(start -0.925 0.47)
			(end 0.925 -0.47)
			(stroke
				(width 0.05)
				(type default)
			)
			(fill no)
			(layer "B.CrtYd")
		)
		(fp_line
			(start -0.494 0.25)
			(end -0.494 -0.248)
			(stroke
				(width 0.15)
				(type solid)
			)
			(layer "B.Fab")
		)
		(fp_line
			(start 0.504 0.25)
			(end -0.494 0.25)
			(stroke
				(width 0.15)
				(type solid)
			)
			(layer "B.Fab")
		)
		(fp_line
			(start -0.494 -0.248)
			(end 0.504 -0.248)
			(stroke
				(width 0.15)
				(type solid)
			)
			(layer "B.Fab")
		)
		(fp_line
			(start 0.504 -0.248)
			(end 0.504 0.25)
			(stroke
				(width 0.15)
				(type solid)
			)
			(layer "B.Fab")
		)
		(pad "1" smd roundrect
			(at -0.48 0 270)
			(size 0.59 0.64)
			(layers "B.Cu" "B.Mask" "B.Paste")
			(roundrect_rratio 0.25)
			(net 1 "GND")
			(pintype "passive")
			(teardrops
				(best_length_ratio 0.2)
				(max_length 1)
				(best_width_ratio 0.9)
				(max_width 2)
				(curved_edges yes)
				(filter_ratio 0.9)
				(enabled yes)
				(allow_two_segments yes)
				(prefer_zone_connections yes)
			)
		)
		(pad "2" smd roundrect
			(at 0.48 0 270)
			(size 0.59 0.64)
			(layers "B.Cu" "B.Mask" "B.Paste")
			(roundrect_rratio 0.25)
			(net 74 "+1V0")
			(pintype "passive")
			(teardrops
				(best_length_ratio 0.2)
				(max_length 1)
				(best_width_ratio 0.9)
				(max_width 2)
				(curved_edges yes)
				(filter_ratio 0.9)
				(enabled yes)
				(allow_two_segments yes)
				(prefer_zone_connections yes)
			)
		)
	)
	(footprint "antmicro-footprints:TP_SMD_0.75mm"
		(layer "B.Cu")
		(at 258.95 85.71 180)
		(property "Reference" "TP12"
			(at 0.399999 -0.4 0)
			(layer "B.SilkS")
			(effects
				(font
					(size 0.7 0.7)
					(thickness 0.15)
				)
				(justify left bottom mirror)
			)
		)
		(property "Value" "TP_0.75mm_SMD"
			(at 0 -1.2 0)
			(layer "B.Fab")
			(effects
				(font
					(size 0.7 0.7)
					(thickness 0.15)
				)
				(justify left bottom mirror)
			)
		)
		(property "Author" "Antmicro"
			(at 517.9 171.42 0)
			(layer "B.Fab")
			(hide yes)
			(effects
				(font
					(size 1 1)
					(thickness 0.15)
				)
				(justify mirror)
			)
		)
		(property "License" "Apache-2.0"
			(at 517.9 171.42 0)
			(layer "B.Fab")
			(hide yes)
			(effects
				(font
					(size 1 1)
					(thickness 0.15)
				)
				(justify mirror)
			)
		)
		(property "MPN" ""
			(at 517.9 171.42 0)
			(layer "B.Fab")
			(hide yes)
			(effects
				(font
					(size 1 1)
					(thickness 0.15)
				)
				(justify mirror)
			)
		)
		(property "Manufacturer" ""
			(at 517.9 171.42 0)
			(layer "B.Fab")
			(hide yes)
			(effects
				(font
					(size 1 1)
					(thickness 0.15)
				)
				(justify mirror)
			)
		)
		(property "Public" "False"
			(at 517.9 171.42 0)
			(layer "B.Fab")
			(hide yes)
			(effects
				(font
					(size 1 1)
					(thickness 0.15)
				)
				(justify mirror)
			)
		)
		(sheetname "Misc")
		(sheetfile "misc.kicad_sch")
		(attr exclude_from_pos_files exclude_from_bom)
		(fp_circle
			(center 0 0)
			(end 0.475 0)
			(stroke
				(width 0.05)
				(type default)
			)
			(fill no)
			(layer "B.CrtYd")
		)
		(pad "1" smd circle
			(at 0 0 180)
			(size 0.75 0.75)
			(layers "B.Cu" "B.Mask")
			(net 704 "Net-(U24-GPIO2)")
			(pinfunction "1")
			(pintype "passive")
			(teardrops
				(best_length_ratio 0.4)
				(max_length 1)
				(best_width_ratio 0.9)
				(max_width 2)
				(curved_edges yes)
				(filter_ratio 0.9)
				(enabled yes)
				(allow_two_segments yes)
				(prefer_zone_connections yes)
			)
		)
	)
	(footprint "antmicro-footprints:C_0603_1608Metric"
		(layer "B.Cu")
		(at 104.65 156.86 180)
		(descr "Capacitor SMD 0603")
		(tags "capacitor 0603")
		(property "Reference" "C36"
			(at -3.15 -1.09 0)
			(layer "B.SilkS")
			(effects
				(font
					(size 0.7 0.7)
					(thickness 0.15)
				)
				(justify left bottom mirror)
			)
		)
		(property "Value" "C_22u_16V_0603"
			(at -1.42757 -1.770288 0)
			(layer "B.Fab")
			(effects
				(font
					(size 0.7 0.7)
					(thickness 0.15)
				)
				(justify left bottom mirror)
			)
		)
		(property "Datasheet" "https://product.samsungsem.com/mlcc/CL10A226MO7JZN.do"
			(at 0 0 180)
			(layer "F.Fab")
			(hide yes)
			(effects
				(font
					(size 1.27 1.27)
					(thickness 0.15)
				)
			)
		)
		(property "Author" "Antmicro"
			(at 209.3 313.72 0)
			(layer "B.Fab")
			(hide yes)
			(effects
				(font
					(size 1 1)
					(thickness 0.15)
				)
				(justify mirror)
			)
		)
		(property "Dielectric" ""
			(at 209.3 313.72 0)
			(layer "B.Fab")
			(hide yes)
			(effects
				(font
					(size 1 1)
					(thickness 0.15)
				)
				(justify mirror)
			)
		)
		(property "License" "Apache-2.0"
			(at 209.3 313.72 0)
			(layer "B.Fab")
			(hide yes)
			(effects
				(font
					(size 1 1)
					(thickness 0.15)
				)
				(justify mirror)
			)
		)
		(property "MPN" "CL10A226MO7JZNC"
			(at 209.3 313.72 0)
			(layer "B.Fab")
			(hide yes)
			(effects
				(font
					(size 1 1)
					(thickness 0.15)
				)
				(justify mirror)
			)
		)
		(property "Manufacturer" "Samsung Electro-Mechanics"
			(at 209.3 313.72 0)
			(layer "B.Fab")
			(hide yes)
			(effects
				(font
					(size 1 1)
					(thickness 0.15)
				)
				(justify mirror)
			)
		)
		(property "Public" "False"
			(at 209.3 313.72 0)
			(layer "B.Fab")
			(hide yes)
			(effects
				(font
					(size 1 1)
					(thickness 0.15)
				)
				(justify mirror)
			)
		)
		(property "Val" "22u"
			(at 209.3 313.72 0)
			(layer "B.Fab")
			(hide yes)
			(effects
				(font
					(size 1 1)
					(thickness 0.15)
				)
				(justify mirror)
			)
		)
		(property "Voltage" "16V"
			(at 209.3 313.72 0)
			(layer "B.Fab")
			(hide yes)
			(effects
				(font
					(size 1 1)
					(thickness 0.15)
				)
				(justify mirror)
			)
		)
		(sheetname "OCuLink")
		(sheetfile "oculink.kicad_sch")
		(attr smd)
		(fp_line
			(start 0.15 0.4)
			(end -0.15 0.4)
			(stroke
				(width 0.15)
				(type solid)
			)
			(layer "B.SilkS")
		)
		(fp_line
			(start 0.15 -0.4)
			(end -0.15 -0.4)
			(stroke
				(width 0.15)
				(type solid)
			)
			(layer "B.SilkS")
		)
		(fp_rect
			(start -1.25 0.65)
			(end 1.25 -0.65)
			(stroke
				(width 0.05)
				(type solid)
			)
			(fill no)
			(layer "B.CrtYd")
		)
		(fp_rect
			(start -0.8 0.4)
			(end 0.8 -0.4)
			(stroke
				(width 0.15)
				(type solid)
			)
			(fill no)
			(layer "B.Fab")
		)
		(pad "1" smd roundrect
			(at -0.7 0 180)
			(size 0.8 1)
			(layers "B.Cu" "B.Mask" "B.Paste")
			(roundrect_rratio 0.2)
			(net 1 "GND")
			(pintype "passive")
			(teardrops
				(best_length_ratio 0.2)
				(max_length 1)
				(best_width_ratio 0.9)
				(max_width 2)
				(curved_edges yes)
				(filter_ratio 0.9)
				(enabled yes)
				(allow_two_segments yes)
				(prefer_zone_connections yes)
			)
		)
		(pad "2" smd roundrect
			(at 0.7 0 180)
			(size 0.8 1)
			(layers "B.Cu" "B.Mask" "B.Paste")
			(roundrect_rratio 0.2)
			(net 59 "/OCuLink/V_{ACT_TX}0")
			(pintype "passive")
			(teardrops
				(best_length_ratio 0.2)
				(max_length 1)
				(best_width_ratio 0.9)
				(max_width 2)
				(curved_edges yes)
				(filter_ratio 0.9)
				(enabled yes)
				(allow_two_segments yes)
				(prefer_zone_connections yes)
			)
		)
	)
	(footprint "antmicro-footprints:TP_SMD_0.75mm"
		(layer "B.Cu")
		(at 143.55 167.21 180)
		(property "Reference" "TP3"
			(at -0.75 0.5 0)
			(layer "B.SilkS")
			(effects
				(font
					(size 0.7 0.7)
					(thickness 0.15)
				)
				(justify left bottom mirror)
			)
		)
		(property "Value" "TP_0.75mm_SMD"
			(at 0 -1.2 0)
			(layer "B.Fab")
			(effects
				(font
					(size 0.7 0.7)
					(thickness 0.15)
				)
				(justify left bottom mirror)
			)
		)
		(property "Author" "Antmicro"
			(at 287.1 334.42 0)
			(layer "B.Fab")
			(hide yes)
			(effects
				(font
					(size 1 1)
					(thickness 0.15)
				)
				(justify mirror)
			)
		)
		(property "License" "Apache-2.0"
			(at 287.1 334.42 0)
			(layer "B.Fab")
			(hide yes)
			(effects
				(font
					(size 1 1)
					(thickness 0.15)
				)
				(justify mirror)
			)
		)
		(property "MPN" ""
			(at 287.1 334.42 0)
			(layer "B.Fab")
			(hide yes)
			(effects
				(font
					(size 1 1)
					(thickness 0.15)
				)
				(justify mirror)
			)
		)
		(property "Manufacturer" ""
			(at 287.1 334.42 0)
			(layer "B.Fab")
			(hide yes)
			(effects
				(font
					(size 1 1)
					(thickness 0.15)
				)
				(justify mirror)
			)
		)
		(property "Public" "False"
			(at 287.1 334.42 0)
			(layer "B.Fab")
			(hide yes)
			(effects
				(font
					(size 1 1)
					(thickness 0.15)
				)
				(justify mirror)
			)
		)
		(sheetname "2xSFP+")
		(sheetfile "2xSFP+.kicad_sch")
		(attr exclude_from_pos_files exclude_from_bom)
		(fp_circle
			(center 0 0)
			(end 0.475 0)
			(stroke
				(width 0.05)
				(type default)
			)
			(fill no)
			(layer "B.CrtYd")
		)
		(pad "1" smd circle
			(at 0 0 180)
			(size 0.75 0.75)
			(layers "B.Cu" "B.Mask")
			(net 162 "Net-(J2A-TX_{FAULT})")
			(pinfunction "1")
			(pintype "passive")
			(teardrops
				(best_length_ratio 0.4)
				(max_length 1)
				(best_width_ratio 0.9)
				(max_width 2)
				(curved_edges yes)
				(filter_ratio 0.9)
				(enabled yes)
				(allow_two_segments yes)
				(prefer_zone_connections yes)
			)
		)
	)
	(footprint "antmicro-footprints:C_0402_1005Metric"
		(layer "B.Cu")
		(at 109.811 166.847571 180)
		(descr "Capacitor SMD 0402")
		(tags "capacitor SMD 0402")
		(property "Reference" "C142"
			(at -3.689 -0.462429 0)
			(layer "B.SilkS")
			(effects
				(font
					(size 0.7 0.7)
					(thickness 0.15)
				)
				(justify left bottom mirror)
			)
		)
		(property "Value" "C_220n_0402"
			(at -1.022927 -2.155213 0)
			(layer "B.Fab")
			(effects
				(font
					(size 0.7 0.7)
					(thickness 0.15)
				)
				(justify left bottom mirror)
			)
		)
		(property "Datasheet" "https://www.yageo.com/en/Chart/Download/pdf/CC0402KRX5R6BB224"
			(at 0 0 180)
			(layer "F.Fab")
			(hide yes)
			(effects
				(font
					(size 1.27 1.27)
					(thickness 0.15)
				)
			)
		)
		(property "Author" "Antmicro"
			(at 219.622 333.695142 0)
			(layer "B.Fab")
			(hide yes)
			(effects
				(font
					(size 1 1)
					(thickness 0.15)
				)
				(justify mirror)
			)
		)
		(property "Dielectric" ""
			(at 219.622 333.695142 0)
			(layer "B.Fab")
			(hide yes)
			(effects
				(font
					(size 1 1)
					(thickness 0.15)
				)
				(justify mirror)
			)
		)
		(property "License" "Apache-2.0"
			(at 219.622 333.695142 0)
			(layer "B.Fab")
			(hide yes)
			(effects
				(font
					(size 1 1)
					(thickness 0.15)
				)
				(justify mirror)
			)
		)
		(property "MPN" "CC0402KRX5R6BB224"
			(at 219.622 333.695142 0)
			(layer "B.Fab")
			(hide yes)
			(effects
				(font
					(size 1 1)
					(thickness 0.15)
				)
				(justify mirror)
			)
		)
		(property "Manufacturer" "YAGEO"
			(at 219.622 333.695142 0)
			(layer "B.Fab")
			(hide yes)
			(effects
				(font
					(size 1 1)
					(thickness 0.15)
				)
				(justify mirror)
			)
		)
		(property "Public" "False"
			(at 219.622 333.695142 0)
			(layer "B.Fab")
			(hide yes)
			(effects
				(font
					(size 1 1)
					(thickness 0.15)
				)
				(justify mirror)
			)
		)
		(property "Val" "220n"
			(at 219.622 333.695142 0)
			(layer "B.Fab")
			(hide yes)
			(effects
				(font
					(size 1 1)
					(thickness 0.15)
				)
				(justify mirror)
			)
		)
		(property "Voltage" ""
			(at 219.622 333.695142 0)
			(layer "B.Fab")
			(hide yes)
			(effects
				(font
					(size 1 1)
					(thickness 0.15)
				)
				(justify mirror)
			)
		)
		(sheetname "PCIe redriver")
		(sheetfile "pcie_redriver.kicad_sch")
		(attr smd)
		(fp_rect
			(start -0.925 0.47)
			(end 0.925 -0.47)
			(stroke
				(width 0.05)
				(type default)
			)
			(fill no)
			(layer "B.CrtYd")
		)
		(fp_line
			(start 0.504 0.25)
			(end -0.494 0.25)
			(stroke
				(width 0.15)
				(type solid)
			)
			(layer "B.Fab")
		)
		(fp_line
			(start 0.504 -0.248)
			(end 0.504 0.25)
			(stroke
				(width 0.15)
				(type solid)
			)
			(layer "B.Fab")
		)
		(fp_line
			(start -0.494 0.25)
			(end -0.494 -0.248)
			(stroke
				(width 0.15)
				(type solid)
			)
			(layer "B.Fab")
		)
		(fp_line
			(start -0.494 -0.248)
			(end 0.504 -0.248)
			(stroke
				(width 0.15)
				(type solid)
			)
			(layer "B.Fab")
		)
		(pad "1" smd roundrect
			(at -0.48 0 180)
			(size 0.59 0.64)
			(layers "B.Cu" "B.Mask" "B.Paste")
			(roundrect_rratio 0.25)
			(net 963 "/PCIe redriver/PCIe_{O}_C.TX0+")
			(pintype "passive")
			(teardrops
				(best_length_ratio 0.2)
				(max_length 1)
				(best_width_ratio 0.9)
				(max_width 2)
				(curved_edges yes)
				(filter_ratio 0.9)
				(enabled yes)
				(allow_two_segments yes)
				(prefer_zone_connections yes)
			)
		)
		(pad "2" smd roundrect
			(at 0.48 0 180)
			(size 0.59 0.64)
			(layers "B.Cu" "B.Mask" "B.Paste")
			(roundrect_rratio 0.25)
			(net 100 "/OCuLink/PCIe_{x4}.TX0+")
			(pintype "passive")
			(teardrops
				(best_length_ratio 0.2)
				(max_length 1)
				(best_width_ratio 0.9)
				(max_width 2)
				(curved_edges yes)
				(filter_ratio 0.9)
				(enabled yes)
				(allow_two_segments yes)
				(prefer_zone_connections yes)
			)
		)
	)
	(footprint "antmicro-footprints:R_0402_1005Metric"
		(layer "B.Cu")
		(at 142.05 169.16 -90)
		(descr "Resistor SMD 0402")
		(tags "resistor SMD 0402")
		(property "Reference" "R52"
			(at -3.9 13.5 90)
			(layer "B.SilkS")
			(effects
				(font
					(size 0.7 0.7)
					(thickness 0.15)
				)
				(justify left bottom mirror)
			)
		)
		(property "Value" "R_1k_0402"
			(at -1.011843 -1.772047 90)
			(layer "B.Fab")
			(effects
				(font
					(size 0.7 0.7)
					(thickness 0.15)
				)
				(justify left bottom mirror)
			)
		)
		(property "Datasheet" "https://www.bourns.com/docs/product-datasheets/cr.pdf"
			(at 0 0 270)
			(layer "F.Fab")
			(hide yes)
			(effects
				(font
					(size 1.27 1.27)
					(thickness 0.15)
				)
			)
		)
		(property "Author" "Antmicro"
			(at -27.11 311.21 0)
			(layer "B.Fab")
			(hide yes)
			(effects
				(font
					(size 1 1)
					(thickness 0.15)
				)
				(justify mirror)
			)
		)
		(property "License" "Apache-2.0"
			(at -27.11 311.21 0)
			(layer "B.Fab")
			(hide yes)
			(effects
				(font
					(size 1 1)
					(thickness 0.15)
				)
				(justify mirror)
			)
		)
		(property "MPN" "CR0402-FX-1001GLF"
			(at -27.11 311.21 0)
			(layer "B.Fab")
			(hide yes)
			(effects
				(font
					(size 1 1)
					(thickness 0.15)
				)
				(justify mirror)
			)
		)
		(property "Manufacturer" "Bourns"
			(at -27.11 311.21 0)
			(layer "B.Fab")
			(hide yes)
			(effects
				(font
					(size 1 1)
					(thickness 0.15)
				)
				(justify mirror)
			)
		)
		(property "Public" "False"
			(at -27.11 311.21 0)
			(layer "B.Fab")
			(hide yes)
			(effects
				(font
					(size 1 1)
					(thickness 0.15)
				)
				(justify mirror)
			)
		)
		(property "Tolerance" "1%"
			(at -27.11 311.21 0)
			(layer "B.Fab")
			(hide yes)
			(effects
				(font
					(size 1 1)
					(thickness 0.15)
				)
				(justify mirror)
			)
		)
		(property "Val" "1k"
			(at -27.11 311.21 0)
			(layer "B.Fab")
			(hide yes)
			(effects
				(font
					(size 1 1)
					(thickness 0.15)
				)
				(justify mirror)
			)
		)
		(sheetname "2xSFP+")
		(sheetfile "2xSFP+.kicad_sch")
		(attr smd)
		(fp_rect
			(start -0.925 0.47)
			(end 0.925 -0.47)
			(stroke
				(width 0.05)
				(type default)
			)
			(fill no)
			(layer "B.CrtYd")
		)
		(fp_rect
			(start -0.5 0.25)
			(end 0.5 -0.25)
			(stroke
				(width 0.15)
				(type solid)
			)
			(fill no)
			(layer "B.Fab")
		)
		(pad "1" smd roundrect
			(at -0.48 0 270)
			(size 0.59 0.64)
			(layers "B.Cu" "B.Mask" "B.Paste")
			(roundrect_rratio 0.25)
			(net 876 "Net-(J2B-TX_{FAULT})")
			(pintype "passive")
			(teardrops
				(best_length_ratio 0.2)
				(max_length 1)
				(best_width_ratio 0.9)
				(max_width 2)
				(curved_edges yes)
				(filter_ratio 0.9)
				(enabled yes)
				(allow_two_segments yes)
				(prefer_zone_connections yes)
			)
		)
		(pad "2" smd roundrect
			(at 0.48 0 270)
			(size 0.59 0.64)
			(layers "B.Cu" "B.Mask" "B.Paste")
			(roundrect_rratio 0.25)
			(net 2 "+3V3")
			(pintype "passive")
			(teardrops
				(best_length_ratio 0.2)
				(max_length 1)
				(best_width_ratio 0.9)
				(max_width 2)
				(curved_edges yes)
				(filter_ratio 0.9)
				(enabled yes)
				(allow_two_segments yes)
				(prefer_zone_connections yes)
			)
		)
	)
)
